# T6G (Grand Teton) — schematic netlist excerpt (pin names and nets, part order shuffled) for the footprints in the layout excerpt that follows; sources: Cadence DE-HDL packaged netlist, KiCad conversion of 04192023_DAF0TMB3IC0_F0TG_MB_C_brd_V02_OCP.brd

R387  Q_RES  2.2K 5% CHIP  pkg 0402LF  page 27 : A = P3V3_AUX ; B = CPU0_CORETYPE2
C2106  Q_CAP  22UF 4V 20% X6S  pkg C0402  page 74 : A = PVDDIO_P1 ; B = GND

(kicad_pcb
	(version 20260206)
	(generator "pcbnew")
	(generator_version "10.0")
	(general
		(thickness 1.6)
		(legacy_teardrops no)
	)
	(paper "A4")
	(title_block
		(title "04192023_DAF0TMB3IC0_F0TG_MB_C_brd_V02_OCP.brd")
		(comment 1 "Grand Teton / footprints 8044-8045 of 8354")
	)
	(layers
		(0 "F.Cu" signal "TOP")
		(4 "In1.Cu" signal "GND")
		(6 "In2.Cu" signal "IN1")
		(8 "In3.Cu" signal "GND1")
		(10 "In4.Cu" signal "IN2")
		(12 "In5.Cu" signal "GND2")
		(14 "In6.Cu" signal "IN3")
		(16 "In7.Cu" signal "GND3")
		(18 "In8.Cu" signal "VCC")
		(20 "In9.Cu" signal "VCC1")
		(22 "In10.Cu" signal "GND4")
		(24 "In11.Cu" signal "IN4")
		(26 "In12.Cu" signal "GND5")
		(28 "In13.Cu" signal "IN5")
		(30 "In14.Cu" signal "GND6")
		(32 "In15.Cu" signal "IN6")
		(34 "In16.Cu" signal "GND7")
		(2 "B.Cu" signal "BOTTOM")
		(9 "F.Adhes" user "F.Adhesive")
		(11 "B.Adhes" user "B.Adhesive")
		(13 "F.Paste" user "Package Geometry/Pastemask Top")
		(15 "B.Paste" user "Package Geometry/Pastemask Bottom")
		(5 "F.SilkS" user "Ref Des/Silkscreen Top")
		(7 "B.SilkS" user "Ref Des/Silkscreen Bottom")
		(1 "F.Mask" user "Board Geometry/Soldermask Top")
		(3 "B.Mask" user "Board Geometry/Soldermask Bottom")
		(17 "Dwgs.User" user "User.Drawings")
		(19 "Cmts.User" user "User.Comments")
		(21 "Eco1.User" user "User.Eco1")
		(23 "Eco2.User" user "User.Eco2")
		(25 "Edge.Cuts" user "Board Geometry/Outline")
		(27 "Margin" user)
		(31 "F.CrtYd" user "Package Geometry/Place Bound Top")
		(29 "B.CrtYd" user "Package Geometry/Place Bound Bottom")
		(35 "F.Fab" user "Ref Des/Assembly Top")
		(33 "B.Fab" user "Ref Des/Assembly Bottom")
	)
	(footprint ""
		(layer "B.Cu")
		(at 321.100958 -203.917296 -90)
		(property "Reference" "R387"
			(at 0 0 90)
			(layer "B.SilkS")
			(hide yes)
			(effects
				(font
					(size 1.27 1.27)
				)
				(justify mirror)
			)
		)
		(property "Value" ""
			(at 0 0 90)
			(layer "B.Fab")
			(effects
				(font
					(size 1.27 1.27)
				)
				(justify mirror)
			)
		)
		(duplicate_pad_numbers_are_jumpers no)
		(fp_line
			(start -0.7874 0.4064)
			(end 0.7874 0.4064)
			(stroke
				(width 0.1524)
				(type default)
			)
			(layer "B.SilkS")
		)
		(fp_line
			(start 0.7874 0.4064)
			(end 0.7874 -0.4064)
			(stroke
				(width 0.1524)
				(type default)
			)
			(layer "B.SilkS")
		)
		(fp_line
			(start -0.7874 -0.4064)
			(end -0.7874 0.4064)
			(stroke
				(width 0.1524)
				(type default)
			)
			(layer "B.SilkS")
		)
		(fp_line
			(start 0.7874 -0.4064)
			(end -0.7874 -0.4064)
			(stroke
				(width 0.1524)
				(type default)
			)
			(layer "B.SilkS")
		)
		(fp_line
			(start -0.67945 0.3048)
			(end -0.120396 0.3048)
			(stroke
				(width 0.1)
				(type default)
			)
			(layer "B.Fab")
		)
		(fp_line
			(start -0.120396 0.3048)
			(end -0.120396 0.2794)
			(stroke
				(width 0.1)
				(type default)
			)
			(layer "B.Fab")
		)
		(fp_line
			(start 0.12065 0.3048)
			(end 0.67945 0.3048)
			(stroke
				(width 0.1)
				(type default)
			)
			(layer "B.Fab")
		)
		(fp_line
			(start 0.67945 0.3048)
			(end 0.67945 -0.305054)
			(stroke
				(width 0.1)
				(type default)
			)
			(layer "B.Fab")
		)
		(fp_line
			(start -0.120396 0.2794)
			(end 0.12065 0.2794)
			(stroke
				(width 0.1)
				(type default)
			)
			(layer "B.Fab")
		)
		(fp_line
			(start 0.12065 0.2794)
			(end 0.12065 0.3048)
			(stroke
				(width 0.1)
				(type default)
			)
			(layer "B.Fab")
		)
		(fp_line
			(start -0.12065 -0.2794)
			(end -0.12065 -0.3048)
			(stroke
				(width 0.1)
				(type default)
			)
			(layer "B.Fab")
		)
		(fp_line
			(start 0.12065 -0.2794)
			(end -0.12065 -0.2794)
			(stroke
				(width 0.1)
				(type default)
			)
			(layer "B.Fab")
		)
		(fp_line
			(start -0.67945 -0.3048)
			(end -0.67945 0.3048)
			(stroke
				(width 0.1)
				(type default)
			)
			(layer "B.Fab")
		)
		(fp_line
			(start -0.12065 -0.3048)
			(end -0.67945 -0.3048)
			(stroke
				(width 0.1)
				(type default)
			)
			(layer "B.Fab")
		)
		(fp_line
			(start 0.12065 -0.305054)
			(end 0.12065 -0.2794)
			(stroke
				(width 0.1)
				(type default)
			)
			(layer "B.Fab")
		)
		(fp_line
			(start 0.67945 -0.305054)
			(end 0.12065 -0.305054)
			(stroke
				(width 0.1)
				(type default)
			)
			(layer "B.Fab")
		)
		(pad "1" smd circle
			(at 0.40005 0 90)
			(size 0 0)
			(layers "B.Cu" "B.Mask" "B.Paste")
			(net "P3V3_AUX")
		)
		(pad "2" smd circle
			(at -0.40005 0 90)
			(size 0 0)
			(layers "B.Cu" "B.Mask" "B.Paste")
			(net "CPU0_CORETYPE2")
		)
	)
	(footprint ""
		(layer "B.Cu")
		(at 100.271834 -261.947152)
		(property "Reference" "C2106"
			(at 0 0 0)
			(layer "B.SilkS")
			(hide yes)
			(effects
				(font
					(size 1.27 1.27)
				)
				(justify mirror)
			)
		)
		(property "Value" ""
			(at 0 0 0)
			(layer "B.Fab")
			(effects
				(font
					(size 1.27 1.27)
				)
				(justify mirror)
			)
		)
		(duplicate_pad_numbers_are_jumpers no)
		(fp_line
			(start -0.7874 -0.4064)
			(end -0.7874 0.4064)
			(stroke
				(width 0.1524)
				(type default)
			)
			(layer "B.SilkS")
		)
		(fp_line
			(start -0.7874 0.4064)
			(end 0.7874 0.4064)
			(stroke
				(width 0.1524)
				(type default)
			)
			(layer "B.SilkS")
		)
		(fp_line
			(start 0.7874 -0.4064)
			(end -0.7874 -0.4064)
			(stroke
				(width 0.1524)
				(type default)
			)
			(layer "B.SilkS")
		)
		(fp_line
			(start 0.7874 0.4064)
			(end 0.7874 -0.4064)
			(stroke
				(width 0.1524)
				(type default)
			)
			(layer "B.SilkS")
		)
		(fp_line
			(start -0.67945 -0.3048)
			(end -0.67945 0.3048)
			(stroke
				(width 0.1)
				(type default)
			)
			(layer "B.Fab")
		)
		(fp_line
			(start -0.67945 0.3048)
			(end -0.120396 0.3048)
			(stroke
				(width 0.1)
				(type default)
			)
			(layer "B.Fab")
		)
		(fp_line
			(start -0.12065 -0.3048)
			(end -0.67945 -0.3048)
			(stroke
				(width 0.1)
				(type default)
			)
			(layer "B.Fab")
		)
		(fp_line
			(start -0.12065 -0.2794)
			(end -0.12065 -0.3048)
			(stroke
				(width 0.1)
				(type default)
			)
			(layer "B.Fab")
		)
		(fp_line
			(start -0.120396 0.2794)
			(end 0.12065 0.2794)
			(stroke
				(width 0.1)
				(type default)
			)
			(layer "B.Fab")
		)
		(fp_line
			(start -0.120396 0.3048)
			(end -0.120396 0.2794)
			(stroke
				(width 0.1)
				(type default)
			)
			(layer "B.Fab")
		)
		(fp_line
			(start 0.12065 -0.305054)
			(end 0.12065 -0.2794)
			(stroke
				(width 0.1)
				(type default)
			)
			(layer "B.Fab")
		)
		(fp_line
			(start 0.12065 -0.2794)
			(end -0.12065 -0.2794)
			(stroke
				(width 0.1)
				(type default)
			)
			(layer "B.Fab")
		)
		(fp_line
			(start 0.12065 0.2794)
			(end 0.12065 0.3048)
			(stroke
				(width 0.1)
				(type default)
			)
			(layer "B.Fab")
		)
		(fp_line
			(start 0.12065 0.3048)
			(end 0.67945 0.3048)
			(stroke
				(width 0.1)
				(type default)
			)
			(layer "B.Fab")
		)
		(fp_line
			(start 0.67945 -0.305054)
			(end 0.12065 -0.305054)
			(stroke
				(width 0.1)
				(type default)
			)
			(layer "B.Fab")
		)
		(fp_line
			(start 0.67945 0.3048)
			(end 0.67945 -0.305054)
			(stroke
				(width 0.1)
				(type default)
			)
			(layer "B.Fab")
		)
		(pad "1" smd circle
			(at 0.40005 0 180)
			(size 0 0)
			(layers "B.Cu" "B.Mask" "B.Paste")
			(net "PVDDIO_P1")
		)
		(pad "2" smd circle
			(at -0.40005 0 180)
			(size 0 0)
			(layers "B.Cu" "B.Mask" "B.Paste")
			(net "GND")
		)
	)
)
